(kicad_pcb
	(version 20240108)
	(generator "pcbnew")
	(generator_version "8.0")
	(general
		(thickness 1.6)
		(legacy_teardrops no)
	)
	(paper "A4")
	(title_block
		(title "Jetson Orin Baseboard OCuLink Expansion")
		(date "2025-03-18")
		(rev "1.1.0")
		(company "Antmicro Ltd")
		(comment 1 "www.antmicro.com")
		(comment 9 "footprints 28-33 of 119")
	)
	(layers
		(0 "F.Cu" signal)
		(1 "In1.Cu" signal)
		(2 "In2.Cu" signal)
		(31 "B.Cu" signal)
		(32 "B.Adhes" user "B.Adhesive")
		(33 "F.Adhes" user "F.Adhesive")
		(34 "B.Paste" user)
		(35 "F.Paste" user)
		(36 "B.SilkS" user "B.Silkscreen")
		(37 "F.SilkS" user "F.Silkscreen")
		(38 "B.Mask" user)
		(39 "F.Mask" user)
		(40 "Dwgs.User" user "User.Drawings")
		(41 "Cmts.User" user "User.Comments")
		(42 "Eco1.User" user "User.Eco1")
		(43 "Eco2.User" user "User.Eco2")
		(44 "Edge.Cuts" user)
		(45 "Margin" user)
		(46 "B.CrtYd" user "B.Courtyard")
		(47 "F.CrtYd" user "F.Courtyard")
		(48 "B.Fab" user)
		(49 "F.Fab" user)
	)
	(footprint "antmicro-footprints:antmicro-logo_scaled_15mm"
		(layer "F.Cu")
		(at 114.2 98.8 90)
		(property "Reference" "N4"
			(at 0.1 -3 90)
			(layer "F.SilkS")
			(hide yes)
			(effects
				(font
					(size 0.7 0.7)
					(thickness 0.15)
				)
				(justify left bottom)
			)
		)
		(property "Value" "antmicro_logo"
			(at 0 3.1 90)
			(layer "F.Fab")
			(hide yes)
			(effects
				(font
					(size 0.7 0.7)
					(thickness 0.15)
				)
				(justify left bottom)
			)
		)
		(property "Footprint" "antmicro-footprints:antmicro-logo_scaled_15mm"
			(at 0 0 90)
			(layer "F.Fab")
			(hide yes)
			(effects
				(font
					(size 1.27 1.27)
					(thickness 0.15)
				)
			)
		)
		(property "Description" "Mechanical part"
			(at 0 0 90)
			(layer "F.Fab")
			(hide yes)
			(effects
				(font
					(size 1.27 1.27)
					(thickness 0.15)
				)
			)
		)
		(property "MPN" ""
			(at 0 0 90)
			(unlocked yes)
			(layer "F.Fab")
			(hide yes)
			(effects
				(font
					(size 1 1)
					(thickness 0.15)
				)
			)
		)
		(property "Manufacturer" ""
			(at 0 0 90)
			(unlocked yes)
			(layer "F.Fab")
			(hide yes)
			(effects
				(font
					(size 1 1)
					(thickness 0.15)
				)
			)
		)
		(property "Author" "Antmicro"
			(at 0 0 90)
			(unlocked yes)
			(layer "F.Fab")
			(hide yes)
			(effects
				(font
					(size 1 1)
					(thickness 0.15)
				)
			)
		)
		(property "License" "Apache-2.0"
			(at 0 0 90)
			(unlocked yes)
			(layer "F.Fab")
			(hide yes)
			(effects
				(font
					(size 1 1)
					(thickness 0.15)
				)
			)
		)
		(sheetname "Root")
		(sheetfile "jetson-orin-baseboard-oculink-expansion.kicad_sch")
		(attr exclude_from_pos_files exclude_from_bom allow_soldermask_bridges)
	)
	(footprint "antmicro-footprints:C_0402_1005Metric"
		(layer "F.Cu")
		(at 144.133 114.08 180)
		(descr "Capacitor SMD 0402")
		(tags "capacitor SMD 0402")
		(property "Reference" "C31"
			(at 0.933 0.38 0)
			(layer "F.SilkS")
			(effects
				(font
					(size 0.7 0.7)
					(thickness 0.15)
				)
				(justify right top)
			)
		)
		(property "Value" "C_100n_0402"
			(at -1.022927 2.155213 0)
			(layer "F.Fab")
			(effects
				(font
					(size 0.7 0.7)
					(thickness 0.15)
				)
				(justify right top)
			)
		)
		(property "Footprint" "antmicro-footprints:C_0402_1005Metric"
			(at 0 0 0)
			(layer "F.Fab")
			(hide yes)
			(effects
				(font
					(size 1.27 1.27)
					(thickness 0.15)
				)
			)
		)
		(property "Datasheet" "https://www.murata.com/products/productdetail?partno=GRM155R61H104KE14%23"
			(at 0 0 0)
			(layer "F.Fab")
			(hide yes)
			(effects
				(font
					(size 1.27 1.27)
					(thickness 0.15)
				)
			)
		)
		(property "Description" "SMD Multilayer Ceramic Capacitor, 0.1 µF, 50 V, 0402 [1005 Metric], ± 10%, X5R, GRM Series"
			(at 0 0 0)
			(layer "F.Fab")
			(hide yes)
			(effects
				(font
					(size 1.27 1.27)
					(thickness 0.15)
				)
			)
		)
		(property "MPN" "GRM155R61H104KE14D"
			(at 0 0 180)
			(unlocked yes)
			(layer "F.Fab")
			(hide yes)
			(effects
				(font
					(size 1 1)
					(thickness 0.15)
				)
			)
		)
		(property "Manufacturer" "Murata"
			(at 0 0 180)
			(unlocked yes)
			(layer "F.Fab")
			(hide yes)
			(effects
				(font
					(size 1 1)
					(thickness 0.15)
				)
			)
		)
		(property "License" "Apache-2.0"
			(at 0 0 180)
			(unlocked yes)
			(layer "F.Fab")
			(hide yes)
			(effects
				(font
					(size 1 1)
					(thickness 0.15)
				)
			)
		)
		(property "Author" "Antmicro"
			(at 0 0 180)
			(unlocked yes)
			(layer "F.Fab")
			(hide yes)
			(effects
				(font
					(size 1 1)
					(thickness 0.15)
				)
			)
		)
		(property "Val" "100n"
			(at 0 0 180)
			(unlocked yes)
			(layer "F.Fab")
			(hide yes)
			(effects
				(font
					(size 1 1)
					(thickness 0.15)
				)
			)
		)
		(property "Voltage" "50V"
			(at 0 0 180)
			(unlocked yes)
			(layer "F.Fab")
			(hide yes)
			(effects
				(font
					(size 1 1)
					(thickness 0.15)
				)
			)
		)
		(property "Dielectric" "X5R"
			(at 0 0 180)
			(unlocked yes)
			(layer "F.Fab")
			(hide yes)
			(effects
				(font
					(size 1 1)
					(thickness 0.15)
				)
			)
		)
		(sheetname "Root")
		(sheetfile "jetson-orin-baseboard-oculink-expansion.kicad_sch")
		(attr smd)
		(fp_rect
			(start -0.925 -0.47)
			(end 0.925 0.47)
			(stroke
				(width 0.05)
				(type default)
			)
			(fill none)
			(layer "F.CrtYd")
		)
		(fp_line
			(start 0.504 0.248)
			(end -0.494 0.248)
			(stroke
				(width 0.15)
				(type solid)
			)
			(layer "F.Fab")
		)
		(fp_line
			(start 0.504 -0.25)
			(end 0.504 0.248)
			(stroke
				(width 0.15)
				(type solid)
			)
			(layer "F.Fab")
		)
		(fp_line
			(start -0.494 0.248)
			(end -0.494 -0.25)
			(stroke
				(width 0.15)
				(type solid)
			)
			(layer "F.Fab")
		)
		(fp_line
			(start -0.494 -0.25)
			(end 0.504 -0.25)
			(stroke
				(width 0.15)
				(type solid)
			)
			(layer "F.Fab")
		)
		(fp_text user "Author: Antmicro"
			(at -0.939 3.399 0)
			(layer "F.Fab")
			(hide yes)
			(effects
				(font
					(size 0.7 0.7)
					(thickness 0.15)
				)
				(justify right top)
			)
		)
		(fp_text user "${REFERENCE}"
			(at -0.939 4.599 0)
			(layer "F.Fab")
			(hide yes)
			(effects
				(font
					(size 0.7 0.7)
					(thickness 0.15)
				)
				(justify right top)
			)
		)
		(fp_text user "License: Apache-2.0"
			(at -0.939 5.799 0)
			(layer "F.Fab")
			(hide yes)
			(effects
				(font
					(size 0.7 0.7)
					(thickness 0.15)
				)
				(justify right top)
			)
		)
		(pad "1" smd roundrect
			(at -0.48 0 180)
			(size 0.59 0.64)
			(layers "F.Cu" "F.Paste" "F.Mask")
			(roundrect_rratio 0.25)
			(net 51 "GND")
			(pintype "passive")
		)
		(pad "2" smd roundrect
			(at 0.48 0 180)
			(size 0.59 0.64)
			(layers "F.Cu" "F.Paste" "F.Mask")
			(roundrect_rratio 0.25)
			(net 134 "Net-(U4-OUT)")
			(pintype "passive")
		)
	)
	(footprint "antmicro-footprints:TP_SMD_0.75mm"
		(layer "F.Cu")
		(at 117.785 123.6675 180)
		(property "Reference" "TP16"
			(at -1.895 1.4075 0)
			(layer "F.SilkS")
			(effects
				(font
					(size 0.7 0.7)
					(thickness 0.15)
				)
				(justify right top)
			)
		)
		(property "Value" "TP_0.75mm_SMD"
			(at 0 1.2 0)
			(layer "F.Fab")
			(effects
				(font
					(size 0.7 0.7)
					(thickness 0.15)
				)
				(justify right top)
			)
		)
		(property "Footprint" "antmicro-footprints:TP_SMD_0.75mm"
			(at 0 0 0)
			(layer "F.Fab")
			(hide yes)
			(effects
				(font
					(size 1.27 1.27)
					(thickness 0.15)
				)
			)
		)
		(property "Description" "SMT test point"
			(at 0 0 0)
			(layer "F.Fab")
			(hide yes)
			(effects
				(font
					(size 1.27 1.27)
					(thickness 0.15)
				)
			)
		)
		(property "MPN" ""
			(at 0 0 180)
			(unlocked yes)
			(layer "F.Fab")
			(hide yes)
			(effects
				(font
					(size 1 1)
					(thickness 0.15)
				)
			)
		)
		(property "Manufacturer" ""
			(at 0 0 180)
			(unlocked yes)
			(layer "F.Fab")
			(hide yes)
			(effects
				(font
					(size 1 1)
					(thickness 0.15)
				)
			)
		)
		(property "Author" "Antmicro"
			(at 0 0 180)
			(unlocked yes)
			(layer "F.Fab")
			(hide yes)
			(effects
				(font
					(size 1 1)
					(thickness 0.15)
				)
			)
		)
		(property "License" "Apache-2.0"
			(at 0 0 180)
			(unlocked yes)
			(layer "F.Fab")
			(hide yes)
			(effects
				(font
					(size 1 1)
					(thickness 0.15)
				)
			)
		)
		(property "Public" "False"
			(at 0 0 180)
			(unlocked yes)
			(layer "F.Fab")
			(hide yes)
			(effects
				(font
					(size 1 1)
					(thickness 0.15)
				)
			)
		)
		(sheetname "Root")
		(sheetfile "jetson-orin-baseboard-oculink-expansion.kicad_sch")
		(attr exclude_from_pos_files exclude_from_bom)
		(fp_circle
			(center 0 0)
			(end 0.475 0)
			(stroke
				(width 0.05)
				(type default)
			)
			(fill none)
			(layer "F.CrtYd")
		)
		(fp_text user "${REFERENCE}"
			(at -0.4 2.7 0)
			(layer "F.Fab")
			(hide yes)
			(effects
				(font
					(size 0.7 0.7)
					(thickness 0.15)
				)
				(justify right top)
			)
		)
		(fp_text user "Author: Antmicro"
			(at -0.4 3.901 0)
			(layer "F.Fab")
			(hide yes)
			(effects
				(font
					(size 0.7 0.7)
					(thickness 0.15)
				)
				(justify right top)
			)
		)
		(fp_text user "License: Apache-2.0"
			(at -0.4 5.101 0)
			(layer "F.Fab")
			(hide yes)
			(effects
				(font
					(size 0.7 0.7)
					(thickness 0.15)
				)
				(justify right top)
			)
		)
		(pad "1" smd circle
			(at 0 0 180)
			(size 0.75 0.75)
			(layers "F.Cu" "F.Mask")
			(net 112 "Net-(U3-~{I2C_{RESET}})")
			(pinfunction "1")
			(pintype "passive")
		)
	)
	(footprint "antmicro-footprints:R_0402_1005Metric"
		(layer "F.Cu")
		(at 144.6 108.6 -90)
		(descr "Resistor SMD 0402")
		(tags "resistor SMD 0402")
		(property "Reference" "R46"
			(at -1.1 1.3 90)
			(layer "F.SilkS")
			(effects
				(font
					(size 0.7 0.7)
					(thickness 0.15)
				)
				(justify right top)
			)
		)
		(property "Value" "R_5k6_0402"
			(at -1.011843 1.772047 90)
			(layer "F.Fab")
			(effects
				(font
					(size 0.7 0.7)
					(thickness 0.15)
				)
				(justify right top)
			)
		)
		(property "Footprint" "antmicro-footprints:R_0402_1005Metric"
			(at 0 0 90)
			(layer "F.Fab")
			(hide yes)
			(effects
				(font
					(size 1.27 1.27)
					(thickness 0.15)
				)
			)
		)
		(property "Datasheet" "https://www.bourns.com/docs/product-datasheets/cr.pdf"
			(at 0 0 90)
			(layer "F.Fab")
			(hide yes)
			(effects
				(font
					(size 1.27 1.27)
					(thickness 0.15)
				)
			)
		)
		(property "Description" "SMD Chip Resistor, 5.6 kohm, ± 1%, 62.5 mW, 0402 [1005 Metric], Thick Film, General Purpose"
			(at 0 0 90)
			(layer "F.Fab")
			(hide yes)
			(effects
				(font
					(size 1.27 1.27)
					(thickness 0.15)
				)
			)
		)
		(property "MPN" "CR0402-FX-5601GLF"
			(at 0 0 -90)
			(unlocked yes)
			(layer "F.Fab")
			(hide yes)
			(effects
				(font
					(size 1 1)
					(thickness 0.15)
				)
			)
		)
		(property "Manufacturer" "Bourns"
			(at 0 0 -90)
			(unlocked yes)
			(layer "F.Fab")
			(hide yes)
			(effects
				(font
					(size 1 1)
					(thickness 0.15)
				)
			)
		)
		(property "License" "Apache-2.0"
			(at 0 0 -90)
			(unlocked yes)
			(layer "F.Fab")
			(hide yes)
			(effects
				(font
					(size 1 1)
					(thickness 0.15)
				)
			)
		)
		(property "Author" "Antmicro"
			(at 0 0 -90)
			(unlocked yes)
			(layer "F.Fab")
			(hide yes)
			(effects
				(font
					(size 1 1)
					(thickness 0.15)
				)
			)
		)
		(property "Val" "5k6"
			(at 0 0 -90)
			(unlocked yes)
			(layer "F.Fab")
			(hide yes)
			(effects
				(font
					(size 1 1)
					(thickness 0.15)
				)
			)
		)
		(property "Tolerance" "1%"
			(at 0 0 -90)
			(unlocked yes)
			(layer "F.Fab")
			(hide yes)
			(effects
				(font
					(size 1 1)
					(thickness 0.15)
				)
			)
		)
		(sheetname "Root")
		(sheetfile "jetson-orin-baseboard-oculink-expansion.kicad_sch")
		(attr smd)
		(fp_rect
			(start -0.925 -0.47)
			(end 0.925 0.47)
			(stroke
				(width 0.05)
				(type default)
			)
			(fill none)
			(layer "F.CrtYd")
		)
		(fp_rect
			(start -0.5 -0.25)
			(end 0.5 0.25)
			(stroke
				(width 0.15)
				(type solid)
			)
			(fill none)
			(layer "F.Fab")
		)
		(fp_text user "Author: Antmicro"
			(at -0.95 4.169 90)
			(layer "F.Fab")
			(hide yes)
			(effects
				(font
					(size 0.7 0.7)
					(thickness 0.15)
				)
				(justify right top)
			)
		)
		(fp_text user "${REFERENCE}"
			(at -0.95 3.168 90)
			(layer "F.Fab")
			(hide yes)
			(effects
				(font
					(size 0.7 0.7)
					(thickness 0.15)
				)
				(justify right top)
			)
		)
		(fp_text user "License: Apache-2.0"
			(at -0.95 5.169 90)
			(layer "F.Fab")
			(hide yes)
			(effects
				(font
					(size 0.7 0.7)
					(thickness 0.15)
				)
				(justify right top)
			)
		)
		(pad "1" smd roundrect
			(at -0.48 0 270)
			(size 0.59 0.64)
			(layers "F.Cu" "F.Paste" "F.Mask")
			(roundrect_rratio 0.25)
			(net 51 "GND")
			(pintype "passive")
		)
		(pad "2" smd roundrect
			(at 0.48 0 270)
			(size 0.59 0.64)
			(layers "F.Cu" "F.Paste" "F.Mask")
			(roundrect_rratio 0.25)
			(net 137 "Net-(U4-ISET)")
			(pintype "passive")
		)
	)
	(footprint "antmicro-footprints:MP_Pad5.4mm_Drill2.7mm"
		(layer "F.Cu")
		(at 135.9 93.5)
		(descr "Mounting Hole 2.7mm, M2.5")
		(tags "mounting hole 2.7mm m2.5")
		(property "Reference" "MP2"
			(at -3.6 -0.4 90)
			(layer "F.SilkS")
			(effects
				(font
					(size 0.7 0.7)
					(thickness 0.15)
				)
				(justify left bottom)
			)
		)
		(property "Value" "MP_Pad5.4mm_Drill2.7mm"
			(at 0 3.6 0)
			(layer "F.Fab")
			(effects
				(font
					(size 0.7 0.7)
					(thickness 0.15)
				)
				(justify left bottom)
			)
		)
		(property "Footprint" "antmicro-footprints:MP_Pad5.4mm_Drill2.7mm"
			(at 0 0 0)
			(layer "F.Fab")
			(hide yes)
			(effects
				(font
					(size 1.27 1.27)
					(thickness 0.15)
				)
			)
		)
		(property "Description" "Mechanical part"
			(at 0 0 0)
			(layer "F.Fab")
			(hide yes)
			(effects
				(font
					(size 1.27 1.27)
					(thickness 0.15)
				)
			)
		)
		(property "Author" "Antmicro"
			(at 0 0 0)
			(unlocked yes)
			(layer "F.Fab")
			(hide yes)
			(effects
				(font
					(size 1 1)
					(thickness 0.15)
				)
			)
		)
		(property "License" "Apache-2.0"
			(at 0 0 0)
			(unlocked yes)
			(layer "F.Fab")
			(hide yes)
			(effects
				(font
					(size 1 1)
					(thickness 0.15)
				)
			)
		)
		(sheetname "Root")
		(sheetfile "jetson-orin-baseboard-oculink-expansion.kicad_sch")
		(attr exclude_from_pos_files exclude_from_bom)
		(fp_circle
			(center 0 0)
			(end 2.95 0)
			(stroke
				(width 0.05)
				(type default)
			)
			(fill none)
			(layer "F.CrtYd")
		)
		(fp_text user "License: Apache-2.0"
			(at -8.4 8.4 0)
			(layer "F.Fab")
			(hide yes)
			(effects
				(font
					(size 0.7 0.7)
					(thickness 0.15)
				)
				(justify left bottom)
			)
		)
		(fp_text user "Author: Antmicro"
			(at -8.4 7.2 0)
			(layer "F.Fab")
			(hide yes)
			(effects
				(font
					(size 0.7 0.7)
					(thickness 0.15)
				)
				(justify left bottom)
			)
		)
		(fp_text user "${REFERENCE}"
			(at -8.4 6 0)
			(layer "F.Fab")
			(hide yes)
			(effects
				(font
					(size 0.7 0.7)
					(thickness 0.15)
				)
				(justify left bottom)
			)
		)
		(pad "1" thru_hole circle
			(at 0 0)
			(size 5.4 5.4)
			(drill 2.7)
			(layers "*.Cu" "*.Mask")
			(remove_unused_layers no)
			(net 51 "GND")
			(pintype "passive")
			(solder_paste_margin_ratio -1)
		)
	)
	(footprint "antmicro-footprints:C_0402_1005Metric"
		(layer "F.Cu")
		(at 129.2 105.919 180)
		(descr "Capacitor SMD 0402")
		(tags "capacitor SMD 0402")
		(property "Reference" "C41"
			(at 0.91 0.37 0)
			(layer "F.SilkS")
			(effects
				(font
					(size 0.7 0.7)
					(thickness 0.15)
				)
				(justify right top)
			)
		)
		(property "Value" "C_220n_0402"
			(at -1.022927 2.155213 0)
			(layer "F.Fab")
			(effects
				(font
					(size 0.7 0.7)
					(thickness 0.15)
				)
				(justify right top)
			)
		)
		(property "Footprint" "antmicro-footprints:C_0402_1005Metric"
			(at 0 0 0)
			(layer "F.Fab")
			(hide yes)
			(effects
				(font
					(size 1.27 1.27)
					(thickness 0.15)
				)
			)
		)
		(property "Datasheet" "https://www.yageo.com/en/Chart/Download/pdf/CC0402KRX5R6BB224"
			(at 0 0 0)
			(layer "F.Fab")
			(hide yes)
			(effects
				(font
					(size 1.27 1.27)
					(thickness 0.15)
				)
			)
		)
		(property "Description" "SMD Multilayer Ceramic Capacitor, 0.22 µF, 10 V, 0402 [1005 Metric], ± 10%, X5R, CC Series"
			(at 0 0 0)
			(layer "F.Fab")
			(hide yes)
			(effects
				(font
					(size 1.27 1.27)
					(thickness 0.15)
				)
			)
		)
		(property "MPN" "CC0402KRX5R6BB224"
			(at 0 0 180)
			(unlocked yes)
			(layer "F.Fab")
			(hide yes)
			(effects
				(font
					(size 1 1)
					(thickness 0.15)
				)
			)
		)
		(property "Manufacturer" "YAGEO"
			(at 0 0 180)
			(unlocked yes)
			(layer "F.Fab")
			(hide yes)
			(effects
				(font
					(size 1 1)
					(thickness 0.15)
				)
			)
		)
		(property "License" "Apache-2.0"
			(at 0 0 180)
			(unlocked yes)
			(layer "F.Fab")
			(hide yes)
			(effects
				(font
					(size 1 1)
					(thickness 0.15)
				)
			)
		)
		(property "Author" "Antmicro"
			(at 0 0 180)
			(unlocked yes)
			(layer "F.Fab")
			(hide yes)
			(effects
				(font
					(size 1 1)
					(thickness 0.15)
				)
			)
		)
		(property "Val" "220n"
			(at 0 0 180)
			(unlocked yes)
			(layer "F.Fab")
			(hide yes)
			(effects
				(font
					(size 1 1)
					(thickness 0.15)
				)
			)
		)
		(property "Voltage" ""
			(at 0 0 180)
			(unlocked yes)
			(layer "F.Fab")
			(hide yes)
			(effects
				(font
					(size 1 1)
					(thickness 0.15)
				)
			)
		)
		(property "Dielectric" ""
			(at 0 0 180)
			(unlocked yes)
			(layer "F.Fab")
			(hide yes)
			(effects
				(font
					(size 1 1)
					(thickness 0.15)
				)
			)
		)
		(property "Public" "False"
			(at 0 0 180)
			(unlocked yes)
			(layer "F.Fab")
			(hide yes)
			(effects
				(font
					(size 1 1)
					(thickness 0.15)
				)
			)
		)
		(sheetname "Root")
		(sheetfile "jetson-orin-baseboard-oculink-expansion.kicad_sch")
		(attr smd)
		(fp_rect
			(start -0.925 -0.47)
			(end 0.925 0.47)
			(stroke
				(width 0.05)
				(type default)
			)
			(fill none)
			(layer "F.CrtYd")
		)
		(fp_line
			(start 0.504 0.248)
			(end -0.494 0.248)
			(stroke
				(width 0.15)
				(type solid)
			)
			(layer "F.Fab")
		)
		(fp_line
			(start 0.504 -0.25)
			(end 0.504 0.248)
			(stroke
				(width 0.15)
				(type solid)
			)
			(layer "F.Fab")
		)
		(fp_line
			(start -0.494 0.248)
			(end -0.494 -0.25)
			(stroke
				(width 0.15)
				(type solid)
			)
			(layer "F.Fab")
		)
		(fp_line
			(start -0.494 -0.25)
			(end 0.504 -0.25)
			(stroke
				(width 0.15)
				(type solid)
			)
			(layer "F.Fab")
		)
		(fp_text user "${REFERENCE}"
			(at -0.939 4.599 0)
			(layer "F.Fab")
			(hide yes)
			(effects
				(font
					(size 0.7 0.7)
					(thickness 0.15)
				)
				(justify right top)
			)
		)
		(fp_text user "License: Apache-2.0"
			(at -0.939 5.799 0)
			(layer "F.Fab")
			(hide yes)
			(effects
				(font
					(size 0.7 0.7)
					(thickness 0.15)
				)
				(justify right top)
			)
		)
		(fp_text user "Author: Antmicro"
			(at -0.939 3.399 0)
			(layer "F.Fab")
			(hide yes)
			(effects
				(font
					(size 0.7 0.7)
					(thickness 0.15)
				)
				(justify right top)
			)
		)
		(pad "1" smd roundrect
			(at -0.48 0 180)
			(size 0.59 0.64)
			(layers "F.Cu" "F.Paste" "F.Mask")
			(roundrect_rratio 0.25)
			(net 75 "/PCIE_{I}_RX1-")
			(pintype "passive")
		)
		(pad "2" smd roundrect
			(at 0.48 0 180)
			(size 0.59 0.64)
			(layers "F.Cu" "F.Paste" "F.Mask")
			(roundrect_rratio 0.25)
			(net 76 "/PCIE_{I}_C.RX1-")
			(pintype "passive")
		)
	)
)
